# TIMECARD (Time Appliance Project (Time Card)) — schematic netlist excerpt (pin names and nets, part order shuffled) for the footprints in the layout excerpt that follows; sources: Cadence DE-HDL packaged netlist, KiCad conversion of R4006-B0001-02_R01.brd

J1  CONN_JACK_1P_GH4_S_TH  2081680-1  pkg P_F_JACK_1P_GH4_RA_P200  page 23
  \1\  = SMA3_SIG_IO_CONN
  GH1  = SG
  GH2  = SG
  GH3  = SG
  GH4  = SG

(kicad_pcb
	(version 20260206)
	(generator "pcbnew")
	(generator_version "10.0")
	(general
		(thickness 1.6)
		(legacy_teardrops no)
	)
	(paper "A4")
	(title_block
		(title "timecard-production-celestica-r4006 — R4006-B0001-02_R01.brd")
		(comment 1 "Time Appliance Project (Time Card) / footprints 174-175 of 1113")
	)
	(layers
		(0 "F.Cu" signal "TOP")
		(4 "In1.Cu" signal "L02_GND1")
		(6 "In2.Cu" signal "L03_SIG1")
		(8 "In3.Cu" signal "L04_GND2")
		(10 "In4.Cu" signal "L05_VCC1")
		(12 "In5.Cu" signal "L06_VCC2")
		(14 "In6.Cu" signal "L07_GND3")
		(16 "In7.Cu" signal "L08_SIG2")
		(18 "In8.Cu" signal "L09_GND4")
		(2 "B.Cu" signal "BOTTOM")
		(9 "F.Adhes" user "F.Adhesive")
		(11 "B.Adhes" user "B.Adhesive")
		(13 "F.Paste" user "Package Geometry/Pastemask Top")
		(15 "B.Paste" user "Package Geometry/Pastemask Bottom")
		(5 "F.SilkS" user "Ref Des/Silkscreen Top")
		(7 "B.SilkS" user "Ref Des/Silkscreen Bottom")
		(1 "F.Mask" user "Board Geometry/Soldermask Top")
		(3 "B.Mask" user "Board Geometry/Soldermask Bottom")
		(17 "Dwgs.User" user "User.Drawings")
		(19 "Cmts.User" user "User.Comments")
		(21 "Eco1.User" user "User.Eco1")
		(23 "Eco2.User" user "User.Eco2")
		(25 "Edge.Cuts" user "Board Geometry/Outline")
		(27 "Margin" user)
		(31 "F.CrtYd" user "Package Geometry/Place Bound Top")
		(29 "B.CrtYd" user "Package Geometry/Place Bound Bottom")
		(35 "F.Fab" user "Ref Des/Assembly Top")
		(33 "B.Fab" user "Ref Des/Assembly Bottom")
	)
	(footprint ""
		(layer "F.Cu")
		(at 4.073906 -32.599884)
		(property "Reference" "J1"
			(at 5.324094 -1.142746 0)
			(unlocked yes)
			(layer "F.SilkS")
			(effects
				(font
					(size 0.7874 0.5842)
					(thickness 0.1524)
				)
			)
		)
		(property "Value" ""
			(at 0 0 0)
			(layer "F.Fab")
			(effects
				(font
					(size 1.27 1.27)
				)
			)
		)
		(property "Device Type" "CONN_JACK_1P_GH4_S_TH-G200-130A"
			(at -5.098288 5.899912 0)
			(unlocked yes)
			(layer "F.Fab")
			(hide yes)
			(effects
				(font
					(size 0.7874 0.5842)
					(thickness 0.1524)
				)
			)
		)
		(property "User Part Number" "PARTNUM*"
			(at -5.098288 7.093712 0)
			(unlocked yes)
			(layer "Cmts.User")
			(hide yes)
			(effects
				(font
					(size 0.7874 0.5842)
					(thickness 0.1524)
				)
			)
		)
		(duplicate_pad_numbers_are_jumpers no)
		(fp_line
			(start -13.953998 -3.937)
			(end 3.937 -3.937)
			(stroke
				(width 0.1)
				(type default)
			)
			(layer "F.SilkS")
		)
		(fp_line
			(start -13.953998 3.937)
			(end -13.953998 -3.937)
			(stroke
				(width 0.1)
				(type default)
			)
			(layer "F.SilkS")
		)
		(fp_line
			(start 3.937 -3.937)
			(end 3.937 3.937)
			(stroke
				(width 0.1)
				(type default)
			)
			(layer "F.SilkS")
		)
		(fp_line
			(start 3.937 3.937)
			(end -13.953998 3.937)
			(stroke
				(width 0.1)
				(type default)
			)
			(layer "F.SilkS")
		)
		(fp_rect
			(start -8.763 8.763)
			(end 8.763 -8.763)
			(stroke
				(width 0)
				(type default)
			)
			(fill no)
			(layer "B.CrtYd")
		)
		(fp_rect
			(start -14.207998 4.191)
			(end 4.191 -4.191)
			(stroke
				(width 0)
				(type default)
			)
			(fill no)
			(layer "F.CrtYd")
		)
		(fp_line
			(start -13.699998 -3.599942)
			(end 3.599942 -3.599942)
			(stroke
				(width 0.1)
				(type default)
			)
			(layer "F.Fab")
		)
		(fp_line
			(start -13.699998 3.599942)
			(end -13.699998 -3.599942)
			(stroke
				(width 0.1)
				(type default)
			)
			(layer "F.Fab")
		)
		(fp_line
			(start 3.599942 -3.599942)
			(end 3.599942 3.599942)
			(stroke
				(width 0.1)
				(type default)
			)
			(layer "F.Fab")
		)
		(fp_line
			(start 3.599942 3.599942)
			(end -13.699998 3.599942)
			(stroke
				(width 0.1)
				(type default)
			)
			(layer "F.Fab")
		)
		(fp_text user "GH3"
			(at -1.533906 4.310634 0)
			(unlocked yes)
			(layer "F.SilkS")
			(effects
				(font
					(size 0.635 0.4064)
					(thickness 0.1524)
				)
			)
		)
		(fp_text user "GH1"
			(at -0.009906 -4.325366 0)
			(unlocked yes)
			(layer "F.SilkS")
			(effects
				(font
					(size 0.635 0.4064)
					(thickness 0.1524)
				)
			)
		)
		(fp_text user "GH4"
			(at 2.276094 4.437634 0)
			(unlocked yes)
			(layer "F.SilkS")
			(effects
				(font
					(size 0.635 0.4064)
					(thickness 0.1524)
				)
			)
		)
		(fp_text user "GH2"
			(at 2.54 -4.50215 0)
			(unlocked yes)
			(layer "F.SilkS")
			(effects
				(font
					(size 0.635 0.4064)
					(thickness 0.1524)
				)
			)
		)
		(fp_text user "1"
			(at 4.015994 0.000254 0)
			(unlocked yes)
			(layer "F.SilkS")
			(effects
				(font
					(size 0.7874 0.5842)
					(thickness 0.1524)
				)
				(justify left)
			)
		)
		(fp_text user "GH3"
			(at -2.803906 4.201668 0)
			(unlocked yes)
			(layer "F.Fab")
			(effects
				(font
					(size 0.7874 0.5842)
					(thickness 0.1524)
				)
			)
		)
		(fp_text user "GH1"
			(at -2.676906 -4.063746 0)
			(unlocked yes)
			(layer "F.Fab")
			(effects
				(font
					(size 0.7874 0.5842)
					(thickness 0.1524)
				)
			)
		)
		(fp_text user "GH2"
			(at 2.54 -4.57073 0)
			(unlocked yes)
			(layer "F.Fab")
			(effects
				(font
					(size 0.7874 0.5842)
					(thickness 0.1524)
				)
			)
		)
		(fp_text user "GH4"
			(at 2.657094 4.191254 0)
			(unlocked yes)
			(layer "F.Fab")
			(effects
				(font
					(size 0.7874 0.5842)
					(thickness 0.1524)
				)
			)
		)
		(fp_text user "1"
			(at 4.191 -0.35433 0)
			(unlocked yes)
			(layer "F.Fab")
			(effects
				(font
					(size 0.7874 0.5842)
					(thickness 0.1524)
				)
				(justify left)
			)
		)
		(pad "1" thru_hole circle
			(at 0 0)
			(size 2.1844 2.1844)
			(drill 1.4986)
			(layers "*.Cu" "*.Mask")
			(remove_unused_layers no)
			(net "SMA3_SIG_IO_CONN")
			(padstack
				(mode front_inner_back)
				(layer "Inner"
					(shape circle)
					(size 2.1844 2.1844)
					(clearance -0.0508)
				)
				(layer "B.Cu"
					(shape circle)
					(size 2.1844 2.1844)
				)
			)
		)
		(pad "GH1" thru_hole circle
			(at -2.54 -2.54)
			(size 2.286 2.286)
			(drill 1.6002)
			(layers "*.Cu" "*.Mask")
			(remove_unused_layers no)
			(net "SG")
			(padstack
				(mode front_inner_back)
				(layer "Inner"
					(shape circle)
					(size 2.286 2.286)
					(clearance -0.0508)
				)
				(layer "B.Cu"
					(shape circle)
					(size 2.286 2.286)
				)
			)
		)
		(pad "GH2" thru_hole circle
			(at 2.54 -2.54)
			(size 2.286 2.286)
			(drill 1.6002)
			(layers "*.Cu" "*.Mask")
			(remove_unused_layers no)
			(net "SG")
			(padstack
				(mode front_inner_back)
				(layer "Inner"
					(shape circle)
					(size 2.286 2.286)
					(clearance -0.0508)
				)
				(layer "B.Cu"
					(shape circle)
					(size 2.286 2.286)
				)
			)
		)
		(pad "GH3" thru_hole circle
			(at -2.54 2.54)
			(size 2.286 2.286)
			(drill 1.6002)
			(layers "*.Cu" "*.Mask")
			(remove_unused_layers no)
			(net "SG")
			(padstack
				(mode front_inner_back)
				(layer "Inner"
					(shape circle)
					(size 2.286 2.286)
					(clearance -0.0508)
				)
				(layer "B.Cu"
					(shape circle)
					(size 2.286 2.286)
				)
			)
		)
		(pad "GH4" thru_hole circle
			(at 2.54 2.54)
			(size 2.286 2.286)
			(drill 1.6002)
			(layers "*.Cu" "*.Mask")
			(remove_unused_layers no)
			(net "SG")
			(padstack
				(mode front_inner_back)
				(layer "Inner"
					(shape circle)
					(size 2.286 2.286)
					(clearance -0.0508)
				)
				(layer "B.Cu"
					(shape circle)
					(size 2.286 2.286)
				)
			)
		)
	)
	(footprint ""
		(layer "F.Cu")
		(at 49.784 -131.699)
		(property "Reference" "SP73"
			(at 0 0 0)
			(layer "F.SilkS")
			(hide yes)
			(effects
				(font
					(size 1.27 1.27)
				)
			)
		)
		(property "Value" ""
			(at 0 0 0)
			(layer "F.Fab")
			(effects
				(font
					(size 1.27 1.27)
				)
			)
		)
		(duplicate_pad_numbers_are_jumpers no)
	)
)
